# TIMECARD (Time Appliance Project (Time Card)) — schematic netlist excerpt (pin names and nets, part order shuffled) for the footprints in the layout excerpt that follows; sources: Cadence DE-HDL packaged netlist, KiCad conversion of R4006-B0001-02_R01.brd

R68  RESISTOR  4.7KOHM 1%  pkg SMC_0402R_H016  page 18 : \1\ = XP3R3V_FPGA ; \2\ = SHT3X_ADDR
C185  CAPACITOR  10UF 25V 20%  pkg SMC_0805R_H057  page 30 : \1\ = XP1R2V_VIN ; \2\ = SG

(kicad_pcb
	(version 20260206)
	(generator "pcbnew")
	(generator_version "10.0")
	(general
		(thickness 1.6)
		(legacy_teardrops no)
	)
	(paper "A4")
	(title_block
		(title "timecard-production-celestica-r4006 — R4006-B0001-02_R01.brd")
		(comment 1 "Time Appliance Project (Time Card) / footprints 663-664 of 1113")
	)
	(layers
		(0 "F.Cu" signal "TOP")
		(4 "In1.Cu" signal "L02_GND1")
		(6 "In2.Cu" signal "L03_SIG1")
		(8 "In3.Cu" signal "L04_GND2")
		(10 "In4.Cu" signal "L05_VCC1")
		(12 "In5.Cu" signal "L06_VCC2")
		(14 "In6.Cu" signal "L07_GND3")
		(16 "In7.Cu" signal "L08_SIG2")
		(18 "In8.Cu" signal "L09_GND4")
		(2 "B.Cu" signal "BOTTOM")
		(9 "F.Adhes" user "F.Adhesive")
		(11 "B.Adhes" user "B.Adhesive")
		(13 "F.Paste" user "Package Geometry/Pastemask Top")
		(15 "B.Paste" user "Package Geometry/Pastemask Bottom")
		(5 "F.SilkS" user "Ref Des/Silkscreen Top")
		(7 "B.SilkS" user "Ref Des/Silkscreen Bottom")
		(1 "F.Mask" user "Board Geometry/Soldermask Top")
		(3 "B.Mask" user "Board Geometry/Soldermask Bottom")
		(17 "Dwgs.User" user "User.Drawings")
		(19 "Cmts.User" user "User.Comments")
		(21 "Eco1.User" user "User.Eco1")
		(23 "Eco2.User" user "User.Eco2")
		(25 "Edge.Cuts" user "Board Geometry/Outline")
		(27 "Margin" user)
		(31 "F.CrtYd" user "Package Geometry/Place Bound Top")
		(29 "B.CrtYd" user "Package Geometry/Place Bound Bottom")
		(35 "F.Fab" user "Ref Des/Assembly Top")
		(33 "B.Fab" user "Ref Des/Assembly Bottom")
	)
	(footprint ""
		(layer "F.Cu")
		(at 94.7928 -75.819 -90)
		(property "Reference" "C185"
			(at -19.304 27.57043 90)
			(unlocked yes)
			(layer "F.SilkS")
			(effects
				(font
					(size 0.7874 0.5842)
					(thickness 0.1524)
				)
			)
		)
		(property "Value" "VAL*"
			(at 0.0762 3.134106 270)
			(unlocked yes)
			(layer "F.Fab")
			(hide yes)
			(effects
				(font
					(size 0.7874 0.5842)
					(thickness 0.1524)
				)
			)
		)
		(property "Device Type" "CAPACITOR-G107-0F106-EM,10UF,2A"
			(at 0.0508 2.194306 270)
			(unlocked yes)
			(layer "F.Fab")
			(hide yes)
			(effects
				(font
					(size 0.7874 0.5842)
					(thickness 0.1524)
				)
			)
		)
		(property "User Part Number" "PARTNUM*"
			(at 0.1016 5.013706 270)
			(unlocked yes)
			(layer "Cmts.User")
			(hide yes)
			(effects
				(font
					(size 0.7874 0.5842)
					(thickness 0.1524)
				)
			)
		)
		(property "Tolerance" "TOL*"
			(at 0.0762 4.048506 270)
			(unlocked yes)
			(layer "Cmts.User")
			(hide yes)
			(effects
				(font
					(size 0.7874 0.5842)
					(thickness 0.1524)
				)
			)
		)
		(duplicate_pad_numbers_are_jumpers no)
		(fp_line
			(start -1.5748 0.9398)
			(end 1.5748 0.9398)
			(stroke
				(width 0.1)
				(type default)
			)
			(layer "F.SilkS")
		)
		(fp_line
			(start 1.5748 0.9398)
			(end 1.5748 -0.9398)
			(stroke
				(width 0.1)
				(type default)
			)
			(layer "F.SilkS")
		)
		(fp_line
			(start -1.5748 -0.9398)
			(end -1.5748 0.9398)
			(stroke
				(width 0.1)
				(type default)
			)
			(layer "F.SilkS")
		)
		(fp_line
			(start 1.5748 -0.9398)
			(end -1.5748 -0.9398)
			(stroke
				(width 0.1)
				(type default)
			)
			(layer "F.SilkS")
		)
		(fp_rect
			(start -1.5748 0.9398)
			(end 1.5748 -0.9398)
			(stroke
				(width 0)
				(type default)
			)
			(fill no)
			(layer "F.CrtYd")
		)
		(fp_line
			(start -1.016 0.635)
			(end 1.016 0.635)
			(stroke
				(width 0.1)
				(type default)
			)
			(layer "F.Fab")
		)
		(fp_line
			(start 1.016 0.635)
			(end 1.016 -0.635)
			(stroke
				(width 0.1)
				(type default)
			)
			(layer "F.Fab")
		)
		(fp_line
			(start -1.016 -0.635)
			(end -1.016 0.635)
			(stroke
				(width 0.1)
				(type default)
			)
			(layer "F.Fab")
		)
		(fp_line
			(start 1.016 -0.635)
			(end -1.016 -0.635)
			(stroke
				(width 0.1)
				(type default)
			)
			(layer "F.Fab")
		)
		(pad "1" smd rect
			(at -0.8382 0 270)
			(size 0.9652 1.3716)
			(layers "F.Cu" "F.Mask" "F.Paste")
			(net "XP1R2V_VIN")
		)
		(pad "2" smd rect
			(at 0.8382 0 270)
			(size 0.9652 1.3716)
			(layers "F.Cu" "F.Mask" "F.Paste")
			(net "SG")
		)
		(zone
			(layer "F.Cu")
			(hatch none 0.5)
			(connect_pads
				(clearance 0)
			)
			(min_thickness 0.25)
			(keepout
				(tracks allowed)
				(vias not_allowed)
				(pads allowed)
				(copperpour not_allowed)
				(footprints allowed)
			)
			(placement
				(enabled no)
				(sheetname "")
			)
			(fill
				(thermal_gap 0.5)
				(thermal_bridge_width 0.5)
				(island_removal_mode 0)
			)
			(polygon
				(pts
					(xy 94.1578 -76.0476) (xy 94.1578 -75.5904) (xy 95.4278 -75.5904) (xy 95.4278 -76.0476)
				)
			)
		)
	)
	(footprint ""
		(layer "F.Cu")
		(at 151.613108 -49.01311 90)
		(property "Reference" "R68"
			(at 0.00127 -2.882138 90)
			(unlocked yes)
			(layer "F.SilkS")
			(effects
				(font
					(size 0.7874 0.5842)
					(thickness 0.1524)
				)
			)
		)
		(property "Value" "VAL*"
			(at 0.02032 2.13233 90)
			(unlocked yes)
			(layer "F.Fab")
			(hide yes)
			(effects
				(font
					(size 0.7874 0.5842)
					(thickness 0.1524)
				)
			)
		)
		(property "Device Type" "RESISTOR-G155-14701-01,4.7KOHMA"
			(at 0.008382 1.210564 90)
			(unlocked yes)
			(layer "F.Fab")
			(hide yes)
			(effects
				(font
					(size 0.7874 0.5842)
					(thickness 0.1524)
				)
			)
		)
		(property "User Part Number" "PARTNUM*"
			(at 0.02032 4.024884 90)
			(unlocked yes)
			(layer "Cmts.User")
			(hide yes)
			(effects
				(font
					(size 0.7874 0.5842)
					(thickness 0.1524)
				)
			)
		)
		(property "Tolerance" "TOL*"
			(at 0.044704 3.05435 90)
			(unlocked yes)
			(layer "Cmts.User")
			(hide yes)
			(effects
				(font
					(size 0.7874 0.5842)
					(thickness 0.1524)
				)
			)
		)
		(duplicate_pad_numbers_are_jumpers no)
		(fp_line
			(start 1.143 -0.5588)
			(end -1.143 -0.5588)
			(stroke
				(width 0.1)
				(type default)
			)
			(layer "F.SilkS")
		)
		(fp_line
			(start -1.143 -0.5588)
			(end -1.143 0.5588)
			(stroke
				(width 0.1)
				(type default)
			)
			(layer "F.SilkS")
		)
		(fp_line
			(start 1.143 0.5588)
			(end 1.143 -0.5588)
			(stroke
				(width 0.1)
				(type default)
			)
			(layer "F.SilkS")
		)
		(fp_line
			(start -1.143 0.5588)
			(end 1.143 0.5588)
			(stroke
				(width 0.1)
				(type default)
			)
			(layer "F.SilkS")
		)
		(fp_rect
			(start 1.143 0.5588)
			(end -1.143 -0.5588)
			(stroke
				(width 0)
				(type default)
			)
			(fill no)
			(layer "F.CrtYd")
		)
		(fp_line
			(start 0.508 -0.3048)
			(end -0.508 -0.3048)
			(stroke
				(width 0.1)
				(type default)
			)
			(layer "F.Fab")
		)
		(fp_line
			(start -0.508 -0.3048)
			(end -0.508 0.3048)
			(stroke
				(width 0.1)
				(type default)
			)
			(layer "F.Fab")
		)
		(fp_line
			(start 0.508 0.3048)
			(end 0.508 -0.3048)
			(stroke
				(width 0.1)
				(type default)
			)
			(layer "F.Fab")
		)
		(fp_line
			(start -0.508 0.3048)
			(end 0.508 0.3048)
			(stroke
				(width 0.1)
				(type default)
			)
			(layer "F.Fab")
		)
		(pad "1" smd rect
			(at -0.5334 0 90)
			(size 0.7112 0.6096)
			(layers "F.Cu" "F.Mask" "F.Paste")
			(net "XP3R3V_FPGA")
		)
		(pad "2" smd rect
			(at 0.5334 0 90)
			(size 0.7112 0.6096)
			(layers "F.Cu" "F.Mask" "F.Paste")
			(net "SHT3X_ADDR")
		)
		(zone
			(layer "F.Cu")
			(hatch none 0.5)
			(connect_pads
				(clearance 0)
			)
			(min_thickness 0.25)
			(keepout
				(tracks allowed)
				(vias not_allowed)
				(pads allowed)
				(copperpour not_allowed)
				(footprints allowed)
			)
			(placement
				(enabled no)
				(sheetname "")
			)
			(fill
				(thermal_gap 0.5)
				(thermal_bridge_width 0.5)
				(island_removal_mode 0)
			)
			(polygon
				(pts
					(xy 151.917908 -49.08931) (xy 151.308308 -49.08931) (xy 151.308308 -48.93691) (xy 151.917908 -48.93691)
				)
			)
		)
	)
)
